FILE_TYPE = CONNECTIVITY;
{Allegro Design Entry HDL 17.2-2016 S081 (4005846) 1/11/2022}
"PAGE_NUMBER" = 170;
0"NC";
1"P3V3_AUX\g";
2"P3V3_AUX\g";
3"P3V3_AUX\g";
4"P3V3_AUX\g";
5"P3V3_AUX\g";
6"P3V3_AUX\g";
7"P3V3_AUX\g";
8"GND\g";
9"GND\g";
10"GND\g";
11"GND\g";
12"GND\g";
13"GND\g";
14"GND\g";
15"GND\g";
16"GND\g";
17"GND\g";
18"GND\g";
19"GND\g";
20"GND\g";
21"GND\g";
22"OCP_V3_2_NOT_PRSNT_RBT_ARB_IN";
23"OCP_V3_2_PRSNT_ALL_R1_N";
24"OCP_SFF_RBT_ARB_IN_MUX1";
25"OCP_SFF_PRSNT_ALL_R3_N";
26"OCP_SFF_NOT_PRSNT_RBT_ARB_IN";
27"OCP_SFF_RBT_ARB_IN";
28"OCP_SFF_RBT_ARB_OUT";
29"OCP_SFF_RBT_ARB_IN_MUX1_R";
30"OCP_SFF_PRSNT_ALL_R_N"CDS_PHYS_NET_NAME"OCP_SFF_PRSNT0_R_N";
31"OCP_SFF_PRSNT23_R_N"CDS_PHYS_NET_NAME"OCP_SFF_PRSNT0_R_N";
32"OCP_SFF_PRSNT01_R_N"CDS_PHYS_NET_NAME"OCP_SFF_PRSNT0_R_N";
33"OCP_SFF_PRSNT1_R_N"CDS_PHYS_NET_NAME"OCP_SFF_PRSNT1_R_N";
34"OCP_SFF_PRSNT0_R_N"CDS_PHYS_NET_NAME"OCP_SFF_PRSNT0_R_N";
35"OCP_V3_2_PRSNT_ALL_R_N"CDS_PHYS_NET_NAME"OCP_SFF_PRSNT0_R_N";
36"OCP_V3_2_PRSNT3_R_N"CDS_PHYS_NET_NAME"OCP_V3_2_PRSNT3_R_N";
37"OCP_V3_2_PRSNT2_R_N"CDS_PHYS_NET_NAME"OCP_V3_2_PRSNT2_R_N";
38"OCP_V3_2_PRSNT0_R_N"CDS_PHYS_NET_NAME"OCP_V3_2_PRSNT0_R_N";
39"OCP_V3_2_PRSNT1_R_N"CDS_PHYS_NET_NAME"OCP_V3_2_PRSNT1_R_N";
40"OCP_SFF_PRSNT3_R_N"CDS_PHYS_NET_NAME"OCP_SFF_PRSNT3_R_N";
41"OCP_SFF_PRSNT2_R_N"CDS_PHYS_NET_NAME"OCP_SFF_PRSNT2_R_N";
42"OCP_SFF_RBT_ARB_IN_MUX2";
43"OCP_SFF_RBT_ARB_IN_MUX2_R";
44"OCP_V3_2_PRSNT_ALL_R3_N";
45"OCP_SFF_RBT_ARB_IN_MUX1";
46"OCP_SFF_RBT_ARB_IN_MUX2";
47"OCP_SFF_PRSNT_ALL_R1_N";
48"OCP_V3_2_RBT_ARB_IN";
49"OCP_V3_2_RBT_ARB_OUT";
50"OCP_V3_2_PRSNT23_R_N"CDS_PHYS_NET_NAME"OCP_SFF_PRSNT0_R_N";
51"OCP_V3_2_PRSNT01_R_N"CDS_PHYS_NET_NAME"OCP_SFF_PRSNT0_R_N";
%"74LVC2G08DP"
"1","(-1725,750)","0","pure_quanta","I1";
;
PART_NUMBER"ALVC2G08K01"
VALUE"74LVC2G08DP"
PART_TYPE"SMLF"
MATERIAL"IC"
$LOCATION"U241"
CDS_LMAN_SYM_OUTLINE"-150,100,150,-100"
NEEDS_NO_SIZE"TRUE"
CDS_LIB"pure_quanta"
CDS_LOCATION"U241"
$SEC"1"
CDS_SEC"1";
"1Y"
$PN"7"51;
"1B"
$PN"2"39;
"1A"
$PN"1"38;
"GND"
$PN"4"8;
"VCC"
$PN"8"2;
%"74LVC2G08DP"
"1","(-1725,2850)","0","pure_quanta","I11";
;
PART_NUMBER"ALVC2G08K01"
PART_TYPE"SMLF"
MATERIAL"IC"
VALUE"74LVC2G08DP"
$LOCATION"U240"
NEEDS_NO_SIZE"TRUE"
CDS_LMAN_SYM_OUTLINE"-150,100,150,-100"
CDS_LIB"pure_quanta"
CDS_LOCATION"U240"
$SEC"1"
CDS_SEC"1";
"1Y"
$PN"7"32;
"1B"
$PN"2"33;
"1A"
$PN"1"34;
"GND"
$PN"4"9;
"VCC"
$PN"8"3;
%"74LVC2G08DP"
"2","(-1725,1950)","0","pure_quanta","I12";
;
PART_NUMBER"ALVC2G08K01"
VALUE"74LVC2G08DP"
PART_TYPE"SMLF"
MATERIAL"IC"
$LOCATION"U240"
CDS_LIB"pure_quanta"
CDS_LMAN_SYM_OUTLINE"-150,100,150,-100"
NEEDS_NO_SIZE"TRUE"
CDS_LOCATION"U240"
$SEC"2"
CDS_SEC"2";
"2Y"
$PN"3"31;
"2B"
$PN"6"40;
"2A"
$PN"5"41;
%"74LVC2G08DP"
"1","(-400,2400)","0","pure_quanta","I13";
;
PART_NUMBER"ALVC2G08K01"
MATERIAL"IC"
VALUE"74LVC2G08DP"
$LOCATION"U242"
PART_TYPE"SMLF"
NEEDS_NO_SIZE"TRUE"
CDS_LMAN_SYM_OUTLINE"-150,100,150,-100"
CDS_LIB"pure_quanta"
CDS_LOCATION"U242"
$SEC"1"
CDS_SEC"1";
"1Y"
$PN"7"30;
"1B"
$PN"2"31;
"1A"
$PN"1"32;
"GND"
$PN"4"12;
"VCC"
$PN"8"1;
%"74LVC2G08DP"
"2","(-400,275)","0","pure_quanta","I14";
;
PART_NUMBER"ALVC2G08K01"
PART_TYPE"SMLF"
MATERIAL"IC"
VALUE"74LVC2G08DP"
$LOCATION"U242"
CDS_LIB"pure_quanta"
CDS_LMAN_SYM_OUTLINE"-150,100,150,-100"
NEEDS_NO_SIZE"TRUE"
CDS_LOCATION"U242"
$SEC"2"
CDS_SEC"2";
"2Y"
$PN"3"35;
"2B"
$PN"6"50;
"2A"
$PN"5"51;
%"NC7SB3157"
"1","(2025,2400)","2","pure_quanta","I15";
;
PART_NUMBER"ALSB3157000"
VALUE"NC7SB3157P6X"
MATERIAL"EMPTY"
$LOCATION"U243"
MANUF_PN"NC7SB3157P6X"
PACK_TYPE"SMLF"
CDS_LMAN_SYM_OUTLINE"-150,50,150,-150"
CDS_LIB"pure_quanta"
CDS_LOCATION"U243"
$SEC"1"
CDS_SEC"1";
"S"
$PN"6"47;
"B0"
$PN"3"28;
"B1"
$PN"1"26;
"VCC"
$PN"5"7;
"GND"
$PN"2"21;
"A"
$PN"4"46;
%"NC7SB3157"
"1","(2025,1550)","2","pure_quanta","I16";
;
PART_NUMBER"ALSB3157000"
VALUE"NC7SB3157P6X"
MATERIAL"EMPTY"
$LOCATION"U244"
CDS_LIB"pure_quanta"
CDS_LMAN_SYM_OUTLINE"-150,50,150,-150"
MANUF_PN"NC7SB3157P6X"
PACK_TYPE"SMLF"
CDS_LOCATION"U244"
$SEC"1"
CDS_SEC"1";
"S"
$PN"6"25;
"B0"
$PN"3"27;
"B1"
$PN"1"26;
"VCC"
$PN"5"6;
"GND"
$PN"2"20;
"A"
$PN"4"29;
%"NC7SB3157"
"1","(2200,275)","2","pure_quanta","I17";
;
PART_NUMBER"ALSB3157000"
VALUE"NC7SB3157P6X"
MATERIAL"EMPTY"
$LOCATION"U246"
MANUF_PN"NC7SB3157P6X"
PACK_TYPE"SMLF"
CDS_LMAN_SYM_OUTLINE"-150,50,150,-150"
CDS_LIB"pure_quanta"
CDS_LOCATION"U246"
$SEC"1"
CDS_SEC"1";
"S"
$PN"6"23;
"B0"
$PN"3"49;
"B1"
$PN"1"22;
"VCC"
$PN"5"5;
"GND"
$PN"2"18;
"A"
$PN"4"45;
%"NC7SB3157"
"1","(2175,-575)","2","pure_quanta","I18";
;
PART_NUMBER"ALSB3157000"
VALUE"NC7SB3157P6X"
MATERIAL"EMPTY"
$LOCATION"U245"
MANUF_PN"NC7SB3157P6X"
PACK_TYPE"SMLF"
CDS_LMAN_SYM_OUTLINE"-150,50,150,-150"
CDS_LIB"pure_quanta"
CDS_LOCATION"U245"
$SEC"1"
CDS_SEC"1";
"S"
$PN"6"44;
"B0"
$PN"3"48;
"B1"
$PN"1"22;
"VCC"
$PN"5"4;
"GND"
$PN"2"17;
"A"
$PN"4"43;
%"UNIVERSAL_GND"
"1","(-1500,950)","0","logical_power","I19";
;
CDS_LIB"logical_power"
HDL_POWER"GND";
"A"10;
%"74LVC2G08DP"
"2","(-1725,-150)","0","pure_quanta","I2";
;
PART_NUMBER"ALVC2G08K01"
PART_TYPE"SMLF"
VALUE"74LVC2G08DP"
MATERIAL"IC"
$LOCATION"U241"
CDS_LIB"pure_quanta"
NEEDS_NO_SIZE"TRUE"
CDS_LMAN_SYM_OUTLINE"-150,100,150,-100"
CDS_LOCATION"U241"
$SEC"2"
CDS_SEC"2";
"2Y"
$PN"3"50;
"2B"
$PN"6"36;
"2A"
$PN"5"37;
%"UNIVERSAL_POWER"
"1","(-1500,1500)","0","logical_power","I20";
;
HDL_POWER"P3V3_AUX"
CDS_LIB"logical_power";
"A"2;
%"Q_CAP"
"1","(-1500,1175)","0","pure_quanta","I21";
;
PART_NUMBER"CH4104K1B00"
PACK_TYPE"0402"
VALUE"0.1UF"
VOLTAGE"25V"
TOLERANCE"10%"
MATERIAL"X7R"
$LOCATION"C1875"
CDS_LIB"pure_quanta"
CDS_LOCATION"C1875"
$SEC"1"
CDS_SEC"1";
"B"
$PN"2"10;
"A"
$PN"1"2;
%"Q_CAP"
"1","(-1600,3250)","0","pure_quanta","I22";
;
PART_NUMBER"CH4104K1B00"
VOLTAGE"25V"
TOLERANCE"10%"
MATERIAL"X7R"
VALUE"0.1UF"
PACK_TYPE"0402"
$LOCATION"C1874"
CDS_LIB"pure_quanta"
CDS_LOCATION"C1874"
$SEC"1"
CDS_SEC"1";
"B"
$PN"2"11;
"A"
$PN"1"3;
%"UNIVERSAL_POWER"
"1","(-1600,3575)","0","logical_power","I23";
;
HDL_POWER"P3V3_AUX"
CDS_LIB"logical_power";
"A"3;
%"UNIVERSAL_GND"
"1","(-1600,3025)","0","logical_power","I24";
;
CDS_LIB"logical_power"
HDL_POWER"GND";
"A"11;
%"UNIVERSAL_GND"
"1","(-1725,2575)","0","logical_power","I25";
;
HDL_POWER"GND"
CDS_LIB"logical_power";
"A"9;
%"UNIVERSAL_GND"
"1","(-1725,475)","0","logical_power","I26";
;
CDS_LIB"logical_power"
HDL_POWER"GND";
"A"8;
%"Q_CAP"
"1","(1525,575)","0","pure_quanta","I27";
;
PART_NUMBER"CH4104K1B00"
MATERIAL"X7R"
TOLERANCE"10%"
VOLTAGE"25V"
PACK_TYPE"0402"
VALUE"0.1UF"
$LOCATION"C1880"
CDS_LIB"pure_quanta"
CDS_LOCATION"C1880"
$SEC"1"
CDS_SEC"1";
"B"
$PN"2"16;
"A"
$PN"1"5;
%"UNIVERSAL_GND"
"1","(1525,350)","0","logical_power","I28";
;
HDL_POWER"GND"
CDS_LIB"logical_power";
"A"16;
%"UNIVERSAL_POWER"
"1","(1525,900)","0","logical_power","I29";
;
HDL_POWER"P3V3_AUX"
CDS_LIB"logical_power";
"A"5;
%"UNIVERSAL_POWER"
"1","(1525,25)","0","logical_power","I30";
;
HDL_POWER"P3V3_AUX"
CDS_LIB"logical_power";
"A"4;
%"Q_CAP"
"1","(1525,-250)","0","pure_quanta","I31";
;
PART_NUMBER"CH4104K1B00"
VOLTAGE"25V"
PACK_TYPE"0402"
MATERIAL"X7R"
TOLERANCE"10%"
VALUE"0.1UF"
$LOCATION"C1879"
CDS_LIB"pure_quanta"
CDS_LOCATION"C1879"
$SEC"1"
CDS_SEC"1";
"B"
$PN"2"15;
"A"
$PN"1"4;
%"UNIVERSAL_GND"
"1","(1525,-475)","0","logical_power","I32";
;
CDS_LIB"logical_power"
HDL_POWER"GND";
"A"15;
%"UNIVERSAL_POWER"
"1","(1325,3100)","0","logical_power","I33";
;
HDL_POWER"P3V3_AUX"
CDS_LIB"logical_power";
"A"7;
%"Q_CAP"
"1","(1325,2775)","0","pure_quanta","I34";
;
PART_NUMBER"CH4104K1B00"
MATERIAL"X7R"
TOLERANCE"10%"
VOLTAGE"25V"
VALUE"0.1UF"
PACK_TYPE"0402"
$LOCATION"C1877"
CDS_LIB"pure_quanta"
CDS_LOCATION"C1877"
$SEC"1"
CDS_SEC"1";
"B"
$PN"2"14;
"A"
$PN"1"7;
%"UNIVERSAL_GND"
"1","(1325,2550)","0","logical_power","I35";
;
HDL_POWER"GND"
CDS_LIB"logical_power";
"A"14;
%"UNIVERSAL_GND"
"1","(1350,1700)","0","logical_power","I36";
;
CDS_LIB"logical_power"
HDL_POWER"GND";
"A"19;
%"Q_CAP"
"1","(1350,1925)","0","pure_quanta","I37";
;
PART_NUMBER"CH4104K1B00"
VOLTAGE"25V"
PACK_TYPE"0402"
MATERIAL"X7R"
TOLERANCE"10%"
VALUE"0.1UF"
$LOCATION"C1878"
CDS_LIB"pure_quanta"
CDS_LOCATION"C1878"
$SEC"1"
CDS_SEC"1";
"B"
$PN"2"19;
"A"
$PN"1"6;
%"UNIVERSAL_POWER"
"1","(1350,2175)","0","logical_power","I38";
;
HDL_POWER"P3V3_AUX"
CDS_LIB"logical_power";
"A"6;
%"UNIVERSAL_GND"
"1","(-325,2625)","0","logical_power","I39";
;
CDS_LIB"logical_power"
HDL_POWER"GND";
"A"13;
%"UNIVERSAL_POWER"
"1","(-325,3175)","0","logical_power","I40";
;
HDL_POWER"P3V3_AUX"
CDS_LIB"logical_power";
"A"1;
%"Q_CAP"
"1","(-325,2850)","0","pure_quanta","I41";
;
PART_NUMBER"CH4104K1B00"
MATERIAL"X7R"
VOLTAGE"25V"
TOLERANCE"10%"
PACK_TYPE"0402"
VALUE"0.1UF"
$LOCATION"C1876"
CDS_LIB"pure_quanta"
CDS_LOCATION"C1876"
$SEC"1"
CDS_SEC"1";
"B"
$PN"2"13;
"A"
$PN"1"1;
%"UNIVERSAL_GND"
"1","(-400,2125)","0","logical_power","I42";
;
CDS_LIB"logical_power"
HDL_POWER"GND";
"A"12;
%"Q_RES"
"1","(825,2400)","0","pure_quanta","I44";
;
PART_NUMBER"CS00002JB13"
VALUE"0"
TOLERANCE"5%"
WATTAGE"1/16W"
PACK_TYPE"0402LF"
MATERIAL"CHIP"
$LOCATION"R3303"
CDS_LIB"pure_quanta"
CDS_LOCATION"R3303"
$SEC"1"
CDS_SEC"1";
"B"
$PN"2"47;
"A"
$PN"1"30;
%"Q_RES"
"1","(625,1550)","0","pure_quanta","I45";
;
PART_NUMBER"CS00002JB13"
VALUE"0"
TOLERANCE"5%"
WATTAGE"1/16W"
PACK_TYPE"0402LF"
MATERIAL"CHIP"
$LOCATION"R3304"
CDS_LIB"pure_quanta"
CDS_LOCATION"R3304"
$SEC"1"
CDS_SEC"1";
"B"
$PN"2"25;
"A"
$PN"1"30;
%"Q_RES"
"1","(825,275)","0","pure_quanta","I46";
;
PART_NUMBER"CS00002JB13"
VALUE"0"
WATTAGE"1/16W"
TOLERANCE"5%"
PACK_TYPE"0402LF"
MATERIAL"CHIP"
$LOCATION"R3308"
CDS_LIB"pure_quanta"
CDS_LOCATION"R3308"
$SEC"1"
CDS_SEC"1";
"B"
$PN"2"23;
"A"
$PN"1"35;
%"Q_RES"
"1","(800,-575)","0","pure_quanta","I47";
;
PART_NUMBER"CS00002JB13"
WATTAGE"1/16W"
TOLERANCE"5%"
MATERIAL"CHIP"
PACK_TYPE"0402LF"
VALUE"0"
$LOCATION"R3306"
CDS_LIB"pure_quanta"
CDS_LOCATION"R3306"
$SEC"1"
CDS_SEC"1";
"B"
$PN"2"44;
"A"
$PN"1"35;
%"Q_RES"
"1","(625,1450)","0","pure_quanta","I50";
;
PART_NUMBER"CS00002JB13"
PACK_TYPE"0402LF"
WATTAGE"1/16W"
TOLERANCE"5%"
VALUE"0"
MATERIAL"CHIP"
$LOCATION"R3305"
CDS_LIB"pure_quanta"
CDS_LOCATION"R3305"
$SEC"1"
CDS_SEC"1";
"B"
$PN"2"29;
"A"
$PN"1"24;
%"Q_RES"
"1","(800,-675)","0","pure_quanta","I52";
;
PART_NUMBER"CS00002JB13"
PACK_TYPE"0402LF"
TOLERANCE"5%"
MATERIAL"CHIP"
VALUE"0"
WATTAGE"1/16W"
$LOCATION"R3307"
CDS_LIB"pure_quanta"
CDS_LOCATION"R3307"
$SEC"1"
CDS_SEC"1";
"B"
$PN"2"43;
"A"
$PN"1"42;
%"UNIVERSAL_GND"
"1","(2375,2175)","0","logical_power","I60";
;
CDS_LIB"logical_power"
HDL_POWER"GND";
"A"21;
%"UNIVERSAL_GND"
"1","(2375,1325)","0","logical_power","I61";
;
HDL_POWER"GND"
CDS_LIB"logical_power";
"A"20;
%"UNIVERSAL_GND"
"1","(2550,50)","0","logical_power","I62";
;
HDL_POWER"GND"
CDS_LIB"logical_power";
"A"18;
%"UNIVERSAL_GND"
"1","(2525,-800)","0","logical_power","I63";
;
HDL_POWER"GND"
CDS_LIB"logical_power";
"A"17;
END.
